# T6G (Grand Teton) — schematic netlist excerpt (pin names and nets, part order shuffled) for the footprints in the layout excerpt that follows; sources: Cadence DE-HDL packaged netlist, KiCad conversion of 04192023_DAF0TMB3IC0_F0TG_MB_C_brd_V02_OCP.brd

C1533  Q_CAP_DIFFBUS  DIFF BUS_0.22UF 6.3V 20% X6S  pkg C0201  page 67 : \1\ = P5E_CPU1_P3_TX_C_DP<7> ; \2\ = P5E_CPU1_P3_TX_DP<7>
R4142  Q_RES  100K 1% CHIP  pkg 0402LF  page 125 : A = P3V3_AUX ; B = PRSNT_CABLE_GPU_A2_ISO_N
PR2529  Q_RES  10 1% CHIP  pkg 0402LF  page 266 : A = P12V_HSC_GATE_G2 ; B = P12V_HSC_GATE2

(kicad_pcb
	(version 20260206)
	(generator "pcbnew")
	(generator_version "10.0")
	(general
		(thickness 1.6)
		(legacy_teardrops no)
	)
	(paper "A4")
	(title_block
		(title "04192023_DAF0TMB3IC0_F0TG_MB_C_brd_V02_OCP.brd")
		(comment 1 "Grand Teton / footprints 1023-1025 of 8354")
	)
	(layers
		(0 "F.Cu" signal "TOP")
		(4 "In1.Cu" signal "GND")
		(6 "In2.Cu" signal "IN1")
		(8 "In3.Cu" signal "GND1")
		(10 "In4.Cu" signal "IN2")
		(12 "In5.Cu" signal "GND2")
		(14 "In6.Cu" signal "IN3")
		(16 "In7.Cu" signal "GND3")
		(18 "In8.Cu" signal "VCC")
		(20 "In9.Cu" signal "VCC1")
		(22 "In10.Cu" signal "GND4")
		(24 "In11.Cu" signal "IN4")
		(26 "In12.Cu" signal "GND5")
		(28 "In13.Cu" signal "IN5")
		(30 "In14.Cu" signal "GND6")
		(32 "In15.Cu" signal "IN6")
		(34 "In16.Cu" signal "GND7")
		(2 "B.Cu" signal "BOTTOM")
		(9 "F.Adhes" user "F.Adhesive")
		(11 "B.Adhes" user "B.Adhesive")
		(13 "F.Paste" user "Package Geometry/Pastemask Top")
		(15 "B.Paste" user "Package Geometry/Pastemask Bottom")
		(5 "F.SilkS" user "Ref Des/Silkscreen Top")
		(7 "B.SilkS" user "Ref Des/Silkscreen Bottom")
		(1 "F.Mask" user "Board Geometry/Soldermask Top")
		(3 "B.Mask" user "Board Geometry/Soldermask Bottom")
		(17 "Dwgs.User" user "User.Drawings")
		(19 "Cmts.User" user "User.Comments")
		(21 "Eco1.User" user "User.Eco1")
		(23 "Eco2.User" user "User.Eco2")
		(25 "Edge.Cuts" user "Board Geometry/Outline")
		(27 "Margin" user)
		(31 "F.CrtYd" user "Package Geometry/Place Bound Top")
		(29 "B.CrtYd" user "Package Geometry/Place Bound Bottom")
		(35 "F.Fab" user "Ref Des/Assembly Top")
		(33 "B.Fab" user "Ref Des/Assembly Bottom")
	)
	(footprint ""
		(layer "F.Cu")
		(at 261.76605 -380.66853)
		(property "Reference" "PR2529"
			(at 0 0 0)
			(layer "F.SilkS")
			(hide yes)
			(effects
				(font
					(size 1.27 1.27)
				)
			)
		)
		(property "Value" ""
			(at 0 0 0)
			(layer "F.Fab")
			(effects
				(font
					(size 1.27 1.27)
				)
			)
		)
		(duplicate_pad_numbers_are_jumpers no)
		(fp_line
			(start -0.7874 -0.4064)
			(end 0.7874 -0.4064)
			(stroke
				(width 0.1524)
				(type default)
			)
			(layer "F.SilkS")
		)
		(fp_line
			(start -0.7874 0.4064)
			(end -0.7874 -0.4064)
			(stroke
				(width 0.1524)
				(type default)
			)
			(layer "F.SilkS")
		)
		(fp_line
			(start 0.7874 -0.4064)
			(end 0.7874 0.4064)
			(stroke
				(width 0.1524)
				(type default)
			)
			(layer "F.SilkS")
		)
		(fp_line
			(start 0.7874 0.4064)
			(end -0.7874 0.4064)
			(stroke
				(width 0.1524)
				(type default)
			)
			(layer "F.SilkS")
		)
		(fp_line
			(start -0.67945 -0.305054)
			(end -0.12065 -0.305054)
			(stroke
				(width 0.1)
				(type default)
			)
			(layer "F.Fab")
		)
		(fp_line
			(start -0.67945 0.3048)
			(end -0.67945 -0.305054)
			(stroke
				(width 0.1)
				(type default)
			)
			(layer "F.Fab")
		)
		(fp_line
			(start -0.12065 -0.305054)
			(end -0.12065 -0.2794)
			(stroke
				(width 0.1)
				(type default)
			)
			(layer "F.Fab")
		)
		(fp_line
			(start -0.12065 -0.2794)
			(end 0.12065 -0.2794)
			(stroke
				(width 0.1)
				(type default)
			)
			(layer "F.Fab")
		)
		(fp_line
			(start -0.12065 0.2794)
			(end -0.12065 0.3048)
			(stroke
				(width 0.1)
				(type default)
			)
			(layer "F.Fab")
		)
		(fp_line
			(start -0.12065 0.3048)
			(end -0.67945 0.3048)
			(stroke
				(width 0.1)
				(type default)
			)
			(layer "F.Fab")
		)
		(fp_line
			(start 0.120396 0.2794)
			(end -0.12065 0.2794)
			(stroke
				(width 0.1)
				(type default)
			)
			(layer "F.Fab")
		)
		(fp_line
			(start 0.120396 0.3048)
			(end 0.120396 0.2794)
			(stroke
				(width 0.1)
				(type default)
			)
			(layer "F.Fab")
		)
		(fp_line
			(start 0.12065 -0.3048)
			(end 0.67945 -0.3048)
			(stroke
				(width 0.1)
				(type default)
			)
			(layer "F.Fab")
		)
		(fp_line
			(start 0.12065 -0.2794)
			(end 0.12065 -0.3048)
			(stroke
				(width 0.1)
				(type default)
			)
			(layer "F.Fab")
		)
		(fp_line
			(start 0.67945 -0.3048)
			(end 0.67945 0.3048)
			(stroke
				(width 0.1)
				(type default)
			)
			(layer "F.Fab")
		)
		(fp_line
			(start 0.67945 0.3048)
			(end 0.120396 0.3048)
			(stroke
				(width 0.1)
				(type default)
			)
			(layer "F.Fab")
		)
		(pad "1" smd circle
			(at -0.40005 0)
			(size 0 0)
			(layers "F.Cu" "F.Mask" "F.Paste")
			(net "P12V_HSC_GATE_G2")
		)
		(pad "2" smd circle
			(at 0.40005 0)
			(size 0 0)
			(layers "F.Cu" "F.Mask" "F.Paste")
			(net "P12V_HSC_GATE2")
		)
	)
	(footprint ""
		(layer "F.Cu")
		(at 122.002296 -375.49963 -90)
		(property "Reference" "C1533"
			(at 0 0 270)
			(layer "F.SilkS")
			(hide yes)
			(effects
				(font
					(size 1.27 1.27)
				)
			)
		)
		(property "Value" ""
			(at 0 0 270)
			(layer "F.Fab")
			(effects
				(font
					(size 1.27 1.27)
				)
			)
		)
		(duplicate_pad_numbers_are_jumpers no)
		(fp_line
			(start -0.299974 0.150114)
			(end -0.299974 -0.150114)
			(stroke
				(width 0.1)
				(type default)
			)
			(layer "F.Fab")
		)
		(fp_line
			(start 0.299974 0.150114)
			(end -0.299974 0.150114)
			(stroke
				(width 0.1)
				(type default)
			)
			(layer "F.Fab")
		)
		(fp_line
			(start -0.299974 -0.150114)
			(end 0.299974 -0.150114)
			(stroke
				(width 0.1)
				(type default)
			)
			(layer "F.Fab")
		)
		(fp_line
			(start 0.299974 -0.150114)
			(end 0.299974 0.150114)
			(stroke
				(width 0.1)
				(type default)
			)
			(layer "F.Fab")
		)
		(pad "1" smd rect
			(at -0.2667 0 270)
			(size 0.3048 0.381)
			(layers "F.Cu" "F.Mask" "F.Paste")
			(net "P5E_CPU1_P3_TX_C_DP<7>")
		)
		(pad "2" smd rect
			(at 0.2667 0 270)
			(size 0.3048 0.381)
			(layers "F.Cu" "F.Mask" "F.Paste")
			(net "P5E_CPU1_P3_TX_DP<7>")
		)
	)
	(footprint ""
		(layer "F.Cu")
		(at 306.420266 -431.256186)
		(property "Reference" "R4142"
			(at 0 0 0)
			(layer "F.SilkS")
			(hide yes)
			(effects
				(font
					(size 1.27 1.27)
				)
			)
		)
		(property "Value" ""
			(at 0 0 0)
			(layer "F.Fab")
			(effects
				(font
					(size 1.27 1.27)
				)
			)
		)
		(duplicate_pad_numbers_are_jumpers no)
		(fp_line
			(start -0.7874 -0.4064)
			(end 0.7874 -0.4064)
			(stroke
				(width 0.1524)
				(type default)
			)
			(layer "F.SilkS")
		)
		(fp_line
			(start -0.7874 0.4064)
			(end -0.7874 -0.4064)
			(stroke
				(width 0.1524)
				(type default)
			)
			(layer "F.SilkS")
		)
		(fp_line
			(start 0.7874 -0.4064)
			(end 0.7874 0.4064)
			(stroke
				(width 0.1524)
				(type default)
			)
			(layer "F.SilkS")
		)
		(fp_line
			(start 0.7874 0.4064)
			(end -0.7874 0.4064)
			(stroke
				(width 0.1524)
				(type default)
			)
			(layer "F.SilkS")
		)
		(fp_line
			(start -0.67945 -0.305054)
			(end -0.12065 -0.305054)
			(stroke
				(width 0.1)
				(type default)
			)
			(layer "F.Fab")
		)
		(fp_line
			(start -0.67945 0.3048)
			(end -0.67945 -0.305054)
			(stroke
				(width 0.1)
				(type default)
			)
			(layer "F.Fab")
		)
		(fp_line
			(start -0.12065 -0.305054)
			(end -0.12065 -0.2794)
			(stroke
				(width 0.1)
				(type default)
			)
			(layer "F.Fab")
		)
		(fp_line
			(start -0.12065 -0.2794)
			(end 0.12065 -0.2794)
			(stroke
				(width 0.1)
				(type default)
			)
			(layer "F.Fab")
		)
		(fp_line
			(start -0.12065 0.2794)
			(end -0.12065 0.3048)
			(stroke
				(width 0.1)
				(type default)
			)
			(layer "F.Fab")
		)
		(fp_line
			(start -0.12065 0.3048)
			(end -0.67945 0.3048)
			(stroke
				(width 0.1)
				(type default)
			)
			(layer "F.Fab")
		)
		(fp_line
			(start 0.120396 0.2794)
			(end -0.12065 0.2794)
			(stroke
				(width 0.1)
				(type default)
			)
			(layer "F.Fab")
		)
		(fp_line
			(start 0.120396 0.3048)
			(end 0.120396 0.2794)
			(stroke
				(width 0.1)
				(type default)
			)
			(layer "F.Fab")
		)
		(fp_line
			(start 0.12065 -0.3048)
			(end 0.67945 -0.3048)
			(stroke
				(width 0.1)
				(type default)
			)
			(layer "F.Fab")
		)
		(fp_line
			(start 0.12065 -0.2794)
			(end 0.12065 -0.3048)
			(stroke
				(width 0.1)
				(type default)
			)
			(layer "F.Fab")
		)
		(fp_line
			(start 0.67945 -0.3048)
			(end 0.67945 0.3048)
			(stroke
				(width 0.1)
				(type default)
			)
			(layer "F.Fab")
		)
		(fp_line
			(start 0.67945 0.3048)
			(end 0.120396 0.3048)
			(stroke
				(width 0.1)
				(type default)
			)
			(layer "F.Fab")
		)
		(pad "1" smd circle
			(at -0.40005 0)
			(size 0 0)
			(layers "F.Cu" "F.Mask" "F.Paste")
			(net "P3V3_AUX")
		)
		(pad "2" smd circle
			(at 0.40005 0)
			(size 0 0)
			(layers "F.Cu" "F.Mask" "F.Paste")
			(net "PRSNT_CABLE_GPU_A2_ISO_N")
		)
	)
)
